# S9S_MB_2U (Grand Teton) — schematic netlist excerpt (pin names and nets, part order shuffled) for the footprints in the layout excerpt that follows; sources: Cadence DE-HDL packaged netlist, KiCad conversion of 03242023_DA0F0TMBIJ0_F0T_Motherboard_J_brd_V01_OCP.brd

R3479  Q_RES  33.2 1% CHIP  pkg 0402LF  page 213 : A = GPU_BASE_STBY_EN ; B = GPU_BASE_STBY_EN_R
R281  Q_RES  240 1% EMPTY  pkg 0402LF  page 119 : A = PVNN_TERM_CPU0 ; B = PU_CPU0_SOCKET_ID2

(kicad_pcb
	(version 20260206)
	(generator "pcbnew")
	(generator_version "10.0")
	(general
		(thickness 1.6)
		(legacy_teardrops no)
	)
	(paper "A4")
	(title_block
		(title "03242023_DA0F0TMBIJ0_F0T_Motherboard_J_brd_V01_OCP.brd")
		(comment 1 "Grand Teton / footprints 5111-5112 of 6105")
	)
	(layers
		(0 "F.Cu" signal "TOP")
		(4 "In1.Cu" signal "GND")
		(6 "In2.Cu" signal "IN1")
		(8 "In3.Cu" signal "GND1")
		(10 "In4.Cu" signal "IN2")
		(12 "In5.Cu" signal "GND2")
		(14 "In6.Cu" signal "IN3")
		(16 "In7.Cu" signal "GND3")
		(18 "In8.Cu" signal "VCC")
		(20 "In9.Cu" signal "VCC1")
		(22 "In10.Cu" signal "GND4")
		(24 "In11.Cu" signal "IN4")
		(26 "In12.Cu" signal "GND5")
		(28 "In13.Cu" signal "IN5")
		(30 "In14.Cu" signal "GND6")
		(32 "In15.Cu" signal "IN6")
		(34 "In16.Cu" signal "GND7")
		(2 "B.Cu" signal "BOTTOM")
		(9 "F.Adhes" user "F.Adhesive")
		(11 "B.Adhes" user "B.Adhesive")
		(13 "F.Paste" user "Package Geometry/Pastemask Top")
		(15 "B.Paste" user "Package Geometry/Pastemask Bottom")
		(5 "F.SilkS" user "Ref Des/Silkscreen Top")
		(7 "B.SilkS" user "Ref Des/Silkscreen Bottom")
		(1 "F.Mask" user "Board Geometry/Soldermask Top")
		(3 "B.Mask" user "Board Geometry/Soldermask Bottom")
		(17 "Dwgs.User" user "User.Drawings")
		(19 "Cmts.User" user "User.Comments")
		(21 "Eco1.User" user "User.Eco1")
		(23 "Eco2.User" user "User.Eco2")
		(25 "Edge.Cuts" user "Board Geometry/Outline")
		(27 "Margin" user)
		(31 "F.CrtYd" user "Package Geometry/Place Bound Top")
		(29 "B.CrtYd" user "Package Geometry/Place Bound Bottom")
		(35 "F.Fab" user "Ref Des/Assembly Top")
		(33 "B.Fab" user "Ref Des/Assembly Bottom")
	)
	(footprint ""
		(layer "B.Cu")
		(at 410.156152 -193.08953 -90)
		(property "Reference" "R281"
			(at 0 0 90)
			(layer "B.SilkS")
			(hide yes)
			(effects
				(font
					(size 1.27 1.27)
				)
				(justify mirror)
			)
		)
		(property "Value" ""
			(at 0 0 90)
			(layer "B.Fab")
			(effects
				(font
					(size 1.27 1.27)
				)
				(justify mirror)
			)
		)
		(duplicate_pad_numbers_are_jumpers no)
		(fp_line
			(start -0.7874 0.4064)
			(end 0.7874 0.4064)
			(stroke
				(width 0.1524)
				(type default)
			)
			(layer "B.SilkS")
		)
		(fp_line
			(start 0.7874 0.4064)
			(end 0.7874 -0.4064)
			(stroke
				(width 0.1524)
				(type default)
			)
			(layer "B.SilkS")
		)
		(fp_line
			(start -0.7874 -0.4064)
			(end -0.7874 0.4064)
			(stroke
				(width 0.1524)
				(type default)
			)
			(layer "B.SilkS")
		)
		(fp_line
			(start 0.7874 -0.4064)
			(end -0.7874 -0.4064)
			(stroke
				(width 0.1524)
				(type default)
			)
			(layer "B.SilkS")
		)
		(fp_line
			(start -0.67945 0.3048)
			(end -0.120396 0.3048)
			(stroke
				(width 0.1)
				(type default)
			)
			(layer "B.Fab")
		)
		(fp_line
			(start -0.120396 0.3048)
			(end -0.120396 0.2794)
			(stroke
				(width 0.1)
				(type default)
			)
			(layer "B.Fab")
		)
		(fp_line
			(start 0.12065 0.3048)
			(end 0.67945 0.3048)
			(stroke
				(width 0.1)
				(type default)
			)
			(layer "B.Fab")
		)
		(fp_line
			(start 0.67945 0.3048)
			(end 0.67945 -0.305054)
			(stroke
				(width 0.1)
				(type default)
			)
			(layer "B.Fab")
		)
		(fp_line
			(start -0.120396 0.2794)
			(end 0.12065 0.2794)
			(stroke
				(width 0.1)
				(type default)
			)
			(layer "B.Fab")
		)
		(fp_line
			(start 0.12065 0.2794)
			(end 0.12065 0.3048)
			(stroke
				(width 0.1)
				(type default)
			)
			(layer "B.Fab")
		)
		(fp_line
			(start -0.12065 -0.2794)
			(end -0.12065 -0.3048)
			(stroke
				(width 0.1)
				(type default)
			)
			(layer "B.Fab")
		)
		(fp_line
			(start 0.12065 -0.2794)
			(end -0.12065 -0.2794)
			(stroke
				(width 0.1)
				(type default)
			)
			(layer "B.Fab")
		)
		(fp_line
			(start -0.67945 -0.3048)
			(end -0.67945 0.3048)
			(stroke
				(width 0.1)
				(type default)
			)
			(layer "B.Fab")
		)
		(fp_line
			(start -0.12065 -0.3048)
			(end -0.67945 -0.3048)
			(stroke
				(width 0.1)
				(type default)
			)
			(layer "B.Fab")
		)
		(fp_line
			(start 0.12065 -0.305054)
			(end 0.12065 -0.2794)
			(stroke
				(width 0.1)
				(type default)
			)
			(layer "B.Fab")
		)
		(fp_line
			(start 0.67945 -0.305054)
			(end 0.12065 -0.305054)
			(stroke
				(width 0.1)
				(type default)
			)
			(layer "B.Fab")
		)
		(pad "1" smd circle
			(at 0.40005 0 90)
			(size 0 0)
			(layers "B.Cu" "B.Mask" "B.Paste")
			(net "PVNN_TERM_CPU0")
		)
		(pad "2" smd circle
			(at -0.40005 0 90)
			(size 0 0)
			(layers "B.Cu" "B.Mask" "B.Paste")
			(net "PU_CPU0_SOCKET_ID2")
		)
	)
	(footprint ""
		(layer "B.Cu")
		(at 157.02788 -112.486948 180)
		(property "Reference" "R3479"
			(at 0 0 0)
			(layer "B.SilkS")
			(hide yes)
			(effects
				(font
					(size 1.27 1.27)
				)
				(justify mirror)
			)
		)
		(property "Value" ""
			(at 0 0 0)
			(layer "B.Fab")
			(effects
				(font
					(size 1.27 1.27)
				)
				(justify mirror)
			)
		)
		(duplicate_pad_numbers_are_jumpers no)
		(fp_line
			(start 0.7874 0.4064)
			(end 0.7874 -0.4064)
			(stroke
				(width 0.1524)
				(type default)
			)
			(layer "B.SilkS")
		)
		(fp_line
			(start 0.7874 -0.4064)
			(end -0.7874 -0.4064)
			(stroke
				(width 0.1524)
				(type default)
			)
			(layer "B.SilkS")
		)
		(fp_line
			(start -0.7874 0.4064)
			(end 0.7874 0.4064)
			(stroke
				(width 0.1524)
				(type default)
			)
			(layer "B.SilkS")
		)
		(fp_line
			(start -0.7874 -0.4064)
			(end -0.7874 0.4064)
			(stroke
				(width 0.1524)
				(type default)
			)
			(layer "B.SilkS")
		)
		(fp_line
			(start 0.67945 0.3048)
			(end 0.67945 -0.305054)
			(stroke
				(width 0.1)
				(type default)
			)
			(layer "B.Fab")
		)
		(fp_line
			(start 0.67945 -0.305054)
			(end 0.12065 -0.305054)
			(stroke
				(width 0.1)
				(type default)
			)
			(layer "B.Fab")
		)
		(fp_line
			(start 0.12065 0.3048)
			(end 0.67945 0.3048)
			(stroke
				(width 0.1)
				(type default)
			)
			(layer "B.Fab")
		)
		(fp_line
			(start 0.12065 0.2794)
			(end 0.12065 0.3048)
			(stroke
				(width 0.1)
				(type default)
			)
			(layer "B.Fab")
		)
		(fp_line
			(start 0.12065 -0.2794)
			(end -0.12065 -0.2794)
			(stroke
				(width 0.1)
				(type default)
			)
			(layer "B.Fab")
		)
		(fp_line
			(start 0.12065 -0.305054)
			(end 0.12065 -0.2794)
			(stroke
				(width 0.1)
				(type default)
			)
			(layer "B.Fab")
		)
		(fp_line
			(start -0.120396 0.3048)
			(end -0.120396 0.2794)
			(stroke
				(width 0.1)
				(type default)
			)
			(layer "B.Fab")
		)
		(fp_line
			(start -0.120396 0.2794)
			(end 0.12065 0.2794)
			(stroke
				(width 0.1)
				(type default)
			)
			(layer "B.Fab")
		)
		(fp_line
			(start -0.12065 -0.2794)
			(end -0.12065 -0.3048)
			(stroke
				(width 0.1)
				(type default)
			)
			(layer "B.Fab")
		)
		(fp_line
			(start -0.12065 -0.3048)
			(end -0.67945 -0.3048)
			(stroke
				(width 0.1)
				(type default)
			)
			(layer "B.Fab")
		)
		(fp_line
			(start -0.67945 0.3048)
			(end -0.120396 0.3048)
			(stroke
				(width 0.1)
				(type default)
			)
			(layer "B.Fab")
		)
		(fp_line
			(start -0.67945 -0.3048)
			(end -0.67945 0.3048)
			(stroke
				(width 0.1)
				(type default)
			)
			(layer "B.Fab")
		)
		(pad "1" smd circle
			(at 0.40005 0)
			(size 0 0)
			(layers "B.Cu" "B.Mask" "B.Paste")
			(net "GPU_BASE_STBY_EN")
		)
		(pad "2" smd circle
			(at -0.40005 0)
			(size 0 0)
			(layers "B.Cu" "B.Mask" "B.Paste")
			(net "GPU_BASE_STBY_EN_R")
		)
	)
)
